# BASEBOARD_FAB2 (Tioga Pass) — schematic netlist excerpt (pin names and nets, part order shuffled) for the footprints in the layout excerpt that follows; sources: Cadence DE-HDL packaged netlist, KiCad conversion of Wiwynn_Tioga_Pass_MB.brd

U3T1  W25Q256FVFIG-GP  pkg MEMORY-G4  page 153
  \hold#/io3\  = PU_BIOS_SPI_HOLD1_N
  VCC  = P3V3_STBY
  \reset#\  = PU_SPI1_RST
  \nc#4\  = TP_SPI_1_6
  \nc#5\  = TP_SPI_1_5
  \nc#6\  = TP_SPI_1_4
  \cs#\  = SPI_CS0_SECONDARY_R_N
  \do/io1\  = SPI_MISO_R1
  \wp#/io2\  = PU_BIOS_SPI_WP1_N
  GND  = GND
  \nc#11\  = TP_SPI_1_3
  \nc#12\  = TP_SPI_1_2
  \nc#13\  = TP_SPI_1_1
  \nc#14\  = TP_SPI_1_0
  \di/io0\  = SPI_SWITCH_MOSI_R1
  CLK  = SPI_CLK_R1

R2T65  RES  0.0 5% CHIP  pkg 0402  page 93 : A = FM_CPU_ERR0_LVT3_R_N ; B = FM_CPU_ERR0_LVT3_K_N

(kicad_pcb
	(version 20260206)
	(generator "pcbnew")
	(generator_version "10.0")
	(general
		(thickness 1.6)
		(legacy_teardrops no)
	)
	(paper "A4")
	(title_block
		(title "Wiwynn_Tioga_Pass_MB.brd")
		(comment 1 "Tioga Pass / footprints 3899-3900 of 4770")
	)
	(layers
		(0 "F.Cu" signal "TOP")
		(4 "In1.Cu" signal "L2GND")
		(6 "In2.Cu" signal "L3")
		(8 "In3.Cu" signal "L4GND")
		(10 "In4.Cu" signal "L5")
		(12 "In5.Cu" signal "L6GND")
		(14 "In6.Cu" signal "L7VCC")
		(16 "In7.Cu" signal "L8VCC")
		(18 "In8.Cu" signal "L9GND")
		(20 "In9.Cu" signal "L10")
		(22 "In10.Cu" signal "L11GND")
		(24 "In11.Cu" signal "L12")
		(26 "In12.Cu" signal "L13GND")
		(2 "B.Cu" signal "BOTTOM")
		(9 "F.Adhes" user "F.Adhesive")
		(11 "B.Adhes" user "B.Adhesive")
		(13 "F.Paste" user "Package Geometry/Pastemask Top")
		(15 "B.Paste" user "Package Geometry/Pastemask Bottom")
		(5 "F.SilkS" user "Ref Des/Silkscreen Top")
		(7 "B.SilkS" user "Ref Des/Silkscreen Bottom")
		(1 "F.Mask" user "Board Geometry/Soldermask Top")
		(3 "B.Mask" user "Board Geometry/Soldermask Bottom")
		(17 "Dwgs.User" user "User.Drawings")
		(19 "Cmts.User" user "User.Comments")
		(21 "Eco1.User" user "User.Eco1")
		(23 "Eco2.User" user "User.Eco2")
		(25 "Edge.Cuts" user "Board Geometry/Outline")
		(27 "Margin" user)
		(31 "F.CrtYd" user "Package Geometry/Place Bound Top")
		(29 "B.CrtYd" user "Package Geometry/Place Bound Bottom")
		(35 "F.Fab" user "Ref Des/Assembly Top")
		(33 "B.Fab" user "Ref Des/Assembly Bottom")
	)
	(footprint ""
		(layer "B.Cu")
		(at 362.270294 -42.369486)
		(property "Reference" "R2T65"
			(at 0 0 0)
			(layer "B.SilkS")
			(hide yes)
			(effects
				(font
					(size 1.27 1.27)
				)
				(justify mirror)
			)
		)
		(property "Value" ""
			(at 0 0 0)
			(layer "B.Fab")
			(effects
				(font
					(size 1.27 1.27)
				)
				(justify mirror)
			)
		)
		(duplicate_pad_numbers_are_jumpers no)
		(fp_poly
			(pts
				(xy 0.2794 -0.1016) (xy -0.2794 -0.1016) (xy -0.2794 0.9906) (xy 0.2794 0.9906)
			)
			(stroke
				(width 0)
				(type default)
			)
			(fill no)
			(layer "B.CrtYd")
		)
		(fp_line
			(start -0.2794 -0.1016)
			(end 0.2794 -0.1016)
			(stroke
				(width 0.1)
				(type default)
			)
			(layer "B.Fab")
		)
		(fp_line
			(start -0.2794 0.9906)
			(end -0.2794 -0.1016)
			(stroke
				(width 0.1)
				(type default)
			)
			(layer "B.Fab")
		)
		(fp_line
			(start 0.2794 -0.1016)
			(end 0.2794 0.9906)
			(stroke
				(width 0.1)
				(type default)
			)
			(layer "B.Fab")
		)
		(fp_line
			(start 0.2794 0.9906)
			(end -0.2794 0.9906)
			(stroke
				(width 0.1)
				(type default)
			)
			(layer "B.Fab")
		)
		(pad "1" smd rect
			(at 0 0 180)
			(size 0.508 0.508)
			(layers "B.Cu" "B.Mask" "B.Paste")
			(net "FM_CPU_ERR0_LVT3_R_N")
		)
		(pad "2" smd rect
			(at 0 0.889 180)
			(size 0.508 0.508)
			(layers "B.Cu" "B.Mask" "B.Paste")
			(net "FM_CPU_ERR0_LVT3_K_N")
		)
		(zone
			(layer "B.Cu")
			(hatch none 0.5)
			(connect_pads
				(clearance 0)
			)
			(min_thickness 0.25)
			(keepout
				(tracks allowed)
				(vias not_allowed)
				(pads allowed)
				(copperpour not_allowed)
				(footprints allowed)
			)
			(placement
				(enabled no)
				(sheetname "")
			)
			(fill
				(thermal_gap 0.5)
				(thermal_bridge_width 0.5)
				(island_removal_mode 0)
			)
			(polygon
				(pts
					(xy 362.524294 -42.115486) (xy 362.016294 -42.115486) (xy 362.016294 -41.734486) (xy 362.524294 -41.734486)
				)
			)
		)
		(zone
			(layer "B.Cu")
			(hatch none 0.5)
			(connect_pads
				(clearance 0)
			)
			(min_thickness 0.25)
			(keepout
				(tracks not_allowed)
				(vias allowed)
				(pads allowed)
				(copperpour not_allowed)
				(footprints allowed)
			)
			(placement
				(enabled no)
				(sheetname "")
			)
			(fill
				(thermal_gap 0.5)
				(thermal_bridge_width 0.5)
				(island_removal_mode 0)
			)
			(polygon
				(pts
					(xy 362.524294 -41.734486) (xy 362.016294 -41.734486) (xy 362.016294 -42.115486) (xy 362.524294 -42.115486)
				)
			)
		)
	)
	(footprint ""
		(layer "B.Cu")
		(at 393.375896 -51.66868 90)
		(property "Reference" "U3T1"
			(at 0 0 90)
			(layer "B.SilkS")
			(hide yes)
			(effects
				(font
					(size 1.27 1.27)
				)
				(justify mirror)
			)
		)
		(property "Value" "*"
			(at 6.7945 -2.3241 90)
			(unlocked yes)
			(layer "B.Fab")
			(hide yes)
			(effects
				(font
					(size 1.27 1.016)
					(thickness 0.1524)
				)
				(justify mirror)
			)
		)
		(property "Device Type" "W25Q256FVFIG-GP_MEMORY-G4-W25QA"
			(at 6.7945 -3.8481 90)
			(unlocked yes)
			(layer "B.Fab")
			(hide yes)
			(effects
				(font
					(size 1.27 1.016)
					(thickness 0.1524)
				)
				(justify mirror)
			)
		)
		(duplicate_pad_numbers_are_jumpers no)
		(fp_line
			(start 5.588 -3.2258)
			(end -4.7498 -3.2258)
			(stroke
				(width 0.1524)
				(type default)
			)
			(layer "B.SilkS")
		)
		(fp_line
			(start -4.7498 -3.2258)
			(end -4.7498 3.2258)
			(stroke
				(width 0.1524)
				(type default)
			)
			(layer "B.SilkS")
		)
		(fp_line
			(start 5.588 -0.50038)
			(end 5.08762 0)
			(stroke
				(width 0.1524)
				(type default)
			)
			(layer "B.SilkS")
		)
		(fp_line
			(start 5.08762 0)
			(end 5.588 0.50038)
			(stroke
				(width 0.1524)
				(type default)
			)
			(layer "B.SilkS")
		)
		(fp_line
			(start 5.588 3.2258)
			(end 5.588 -3.2258)
			(stroke
				(width 0.1524)
				(type default)
			)
			(layer "B.SilkS")
		)
		(fp_line
			(start 5.4102 3.2258)
			(end 5.4102 5.7912)
			(stroke
				(width 0.508)
				(type default)
			)
			(layer "B.SilkS")
		)
		(fp_line
			(start -4.7498 3.2258)
			(end 5.588 3.2258)
			(stroke
				(width 0.1524)
				(type default)
			)
			(layer "B.SilkS")
		)
		(fp_poly
			(pts
				(xy 4.764786 -3.2258) (xy -4.7625 -3.2258) (xy -4.7625 3.2258) (xy 4.764786 3.2258)
			)
			(stroke
				(width 0)
				(type default)
			)
			(fill yes)
			(layer "B.SilkS")
		)
		(fp_rect
			(start 5.1435 5.1562)
			(end -5.1435 -5.1562)
			(stroke
				(width 0)
				(type default)
			)
			(fill no)
			(layer "B.CrtYd")
		)
		(fp_poly
			(pts
				(xy 5.6642 6.0452) (xy 5.6642 -6.0452) (xy -5.6642 -6.0452) (xy -5.6642 -1.7653) (xy -5.1435 -1.7653)
				(xy -5.1435 -5.1562) (xy 5.1435 -5.1562) (xy 5.1435 5.1562) (xy -5.1435 5.1562) (xy -5.1435 -1.7526)
				(xy -5.6642 -1.7526) (xy -5.6642 6.0452)
			)
			(stroke
				(width 0)
				(type default)
			)
			(fill no)
			(layer "B.CrtYd")
		)
		(fp_rect
			(start 5.6642 6.0452)
			(end -5.6642 -6.0452)
			(stroke
				(width 0)
				(type default)
			)
			(fill no)
			(layer "B.Fab")
		)
		(pad "1" smd rect
			(at 4.445 4.71805 270)
			(size 0.635 1.651)
			(layers "B.Cu" "B.Mask" "B.Paste")
			(net "PU_BIOS_SPI_HOLD1_N")
		)
		(pad "2" smd rect
			(at 3.175 4.71805 270)
			(size 0.635 1.651)
			(layers "B.Cu" "B.Mask" "B.Paste")
			(net "P3V3_STBY")
		)
		(pad "3" smd rect
			(at 1.905 4.71805 270)
			(size 0.635 1.651)
			(layers "B.Cu" "B.Mask" "B.Paste")
			(net "PU_SPI1_RST")
		)
		(pad "4" smd rect
			(at 0.635 4.71805 270)
			(size 0.635 1.651)
			(layers "B.Cu" "B.Mask" "B.Paste")
			(net "TP_SPI_1_6")
		)
		(pad "5" smd rect
			(at -0.635 4.71805 270)
			(size 0.635 1.651)
			(layers "B.Cu" "B.Mask" "B.Paste")
			(net "TP_SPI_1_5")
		)
		(pad "6" smd rect
			(at -1.905 4.71805 270)
			(size 0.635 1.651)
			(layers "B.Cu" "B.Mask" "B.Paste")
			(net "TP_SPI_1_4")
		)
		(pad "7" smd rect
			(at -3.175 4.71805 270)
			(size 0.635 1.651)
			(layers "B.Cu" "B.Mask" "B.Paste")
			(net "SPI_CS0_SECONDARY_R_N")
		)
		(pad "8" smd rect
			(at -4.445 4.71805 270)
			(size 0.635 1.651)
			(layers "B.Cu" "B.Mask" "B.Paste")
			(net "SPI_MISO_R1")
		)
		(pad "9" smd rect
			(at -4.445 -4.71805 270)
			(size 0.635 1.651)
			(layers "B.Cu" "B.Mask" "B.Paste")
			(net "PU_BIOS_SPI_WP1_N")
		)
		(pad "10" smd rect
			(at -3.175 -4.71805 270)
			(size 0.635 1.651)
			(layers "B.Cu" "B.Mask" "B.Paste")
			(net "GND")
		)
		(pad "11" smd rect
			(at -1.905 -4.71805 270)
			(size 0.635 1.651)
			(layers "B.Cu" "B.Mask" "B.Paste")
			(net "TP_SPI_1_3")
		)
		(pad "12" smd rect
			(at -0.635 -4.71805 270)
			(size 0.635 1.651)
			(layers "B.Cu" "B.Mask" "B.Paste")
			(net "TP_SPI_1_2")
		)
		(pad "13" smd rect
			(at 0.635 -4.71805 270)
			(size 0.635 1.651)
			(layers "B.Cu" "B.Mask" "B.Paste")
			(net "TP_SPI_1_1")
		)
		(pad "14" smd rect
			(at 1.905 -4.71805 270)
			(size 0.635 1.651)
			(layers "B.Cu" "B.Mask" "B.Paste")
			(net "TP_SPI_1_0")
		)
		(pad "15" smd rect
			(at 3.175 -4.71805 270)
			(size 0.635 1.651)
			(layers "B.Cu" "B.Mask" "B.Paste")
			(net "SPI_SWITCH_MOSI_R1")
		)
		(pad "16" smd rect
			(at 4.445 -4.71805 270)
			(size 0.635 1.651)
			(layers "B.Cu" "B.Mask" "B.Paste")
			(net "SPI_CLK_R1")
		)
	)
)
